(kicad_pcb
	(version 20260206)
	(generator "pcbnew")
	(generator_version "10.0")
	(general
		(thickness 1.6)
		(legacy_teardrops no)
	)
	(paper "A4")
	(title_block
		(title "v1-chassis-manager — T6M_CM_d_v01_1031_1645.brd")
		(comment 1 "Open CloudServer (Microsoft) / footprints 992-1001 of 2512")
	)
	(layers
		(0 "F.Cu" signal "TOP")
		(4 "In1.Cu" signal "GND1")
		(6 "In2.Cu" signal "IN1")
		(8 "In3.Cu" signal "VCC1")
		(10 "In4.Cu" signal "VCC2")
		(12 "In5.Cu" signal "GND2")
		(14 "In6.Cu" signal "IN2")
		(16 "In7.Cu" signal "IN3")
		(18 "In8.Cu" signal "GND3")
		(2 "B.Cu" signal "BOTTOM")
		(9 "F.Adhes" user "F.Adhesive")
		(11 "B.Adhes" user "B.Adhesive")
		(13 "F.Paste" user "Package Geometry/Pastemask Top")
		(15 "B.Paste" user "Package Geometry/Pastemask Bottom")
		(5 "F.SilkS" user "Ref Des/Silkscreen Top")
		(7 "B.SilkS" user "Ref Des/Silkscreen Bottom")
		(1 "F.Mask" user "Board Geometry/Soldermask Top")
		(3 "B.Mask" user "Board Geometry/Soldermask Bottom")
		(17 "Dwgs.User" user "User.Drawings")
		(19 "Cmts.User" user "User.Comments")
		(21 "Eco1.User" user "User.Eco1")
		(23 "Eco2.User" user "User.Eco2")
		(25 "Edge.Cuts" user "Board Geometry/Outline")
		(27 "Margin" user)
		(31 "F.CrtYd" user "Package Geometry/Place Bound Top")
		(29 "B.CrtYd" user "Package Geometry/Place Bound Bottom")
		(35 "F.Fab" user "Ref Des/Assembly Top")
		(33 "B.Fab" user "Ref Des/Assembly Bottom")
	)
	(footprint ""
		(layer "F.Cu")
		(at 166.41318 -161.39541 90)
		(property "Reference" "R584"
			(at -8.09117 17.462754 90)
			(unlocked yes)
			(layer "F.SilkS")
			(effects
				(font
					(size 0.7874 0.5842)
					(thickness 0.1524)
				)
				(justify left)
			)
		)
		(property "Value" ""
			(at 0 0 90)
			(layer "F.Fab")
			(effects
				(font
					(size 1.27 1.27)
				)
			)
		)
		(duplicate_pad_numbers_are_jumpers no)
		(fp_line
			(start 0.7874 -0.4064)
			(end 0.7874 0.4064)
			(stroke
				(width 0.1524)
				(type default)
			)
			(layer "F.SilkS")
		)
		(fp_line
			(start -0.7874 -0.4064)
			(end 0.7874 -0.4064)
			(stroke
				(width 0.1524)
				(type default)
			)
			(layer "F.SilkS")
		)
		(fp_line
			(start 0.7874 0.4064)
			(end -0.7874 0.4064)
			(stroke
				(width 0.1524)
				(type default)
			)
			(layer "F.SilkS")
		)
		(fp_line
			(start -0.7874 0.4064)
			(end -0.7874 -0.4064)
			(stroke
				(width 0.1524)
				(type default)
			)
			(layer "F.SilkS")
		)
		(fp_poly
			(pts
				(xy -0.508 0.2794) (xy -0.508 0.2286) (xy -0.635 0.2286) (xy -0.635 -0.254) (xy -0.5334 -0.254)
				(xy -0.5334 -0.2794) (xy 0.5334 -0.2794) (xy 0.5334 -0.254) (xy 0.635 -0.254) (xy 0.635 0.254) (xy 0.5334 0.254)
				(xy 0.5334 0.2794)
			)
			(stroke
				(width 0)
				(type default)
			)
			(fill no)
			(layer "F.CrtYd")
		)
		(pad "1" smd rect
			(at 0.40005 0 90)
			(size 0.4572 0.508)
			(layers "F.Cu" "F.Mask" "F.Paste")
			(net "GND")
		)
		(pad "2" smd rect
			(at -0.40005 0 90)
			(size 0.4572 0.508)
			(layers "F.Cu" "F.Mask" "F.Paste")
			(net "LAN2_NC_SI_CLK_IN")
		)
	)
	(footprint ""
		(layer "F.Cu")
		(at 56.065166 -96.709992 90)
		(property "Reference" "R497"
			(at -54.98719 28.432252 90)
			(unlocked yes)
			(layer "F.SilkS")
			(effects
				(font
					(size 0.7874 0.5842)
					(thickness 0.1524)
				)
				(justify left)
			)
		)
		(property "Value" ""
			(at 0 0 90)
			(layer "F.Fab")
			(effects
				(font
					(size 1.27 1.27)
				)
			)
		)
		(duplicate_pad_numbers_are_jumpers no)
		(fp_line
			(start 0.7874 -0.4064)
			(end 0.7874 0.4064)
			(stroke
				(width 0.1524)
				(type default)
			)
			(layer "F.SilkS")
		)
		(fp_line
			(start -0.7874 -0.4064)
			(end 0.7874 -0.4064)
			(stroke
				(width 0.1524)
				(type default)
			)
			(layer "F.SilkS")
		)
		(fp_line
			(start 0.7874 0.4064)
			(end -0.7874 0.4064)
			(stroke
				(width 0.1524)
				(type default)
			)
			(layer "F.SilkS")
		)
		(fp_line
			(start -0.7874 0.4064)
			(end -0.7874 -0.4064)
			(stroke
				(width 0.1524)
				(type default)
			)
			(layer "F.SilkS")
		)
		(fp_poly
			(pts
				(xy -0.508 0.2794) (xy -0.508 0.2286) (xy -0.635 0.2286) (xy -0.635 -0.254) (xy -0.5334 -0.254)
				(xy -0.5334 -0.2794) (xy 0.5334 -0.2794) (xy 0.5334 -0.254) (xy 0.635 -0.254) (xy 0.635 0.254) (xy 0.5334 0.254)
				(xy 0.5334 0.2794)
			)
			(stroke
				(width 0)
				(type default)
			)
			(fill no)
			(layer "F.CrtYd")
		)
		(pad "1" smd rect
			(at 0.40005 0 90)
			(size 0.4572 0.508)
			(layers "F.Cu" "F.Mask" "F.Paste")
			(net "GND")
		)
		(pad "2" smd rect
			(at -0.40005 0 90)
			(size 0.4572 0.508)
			(layers "F.Cu" "F.Mask" "F.Paste")
			(net "PD_CPU_NODE1_DFX_GPIO_GRP0_0")
		)
	)
	(footprint ""
		(layer "F.Cu")
		(at 96.278954 -15.891764 90)
		(property "Reference" "R191"
			(at 0.643636 -0.886968 90)
			(unlocked yes)
			(layer "F.SilkS")
			(effects
				(font
					(size 0.7874 0.5842)
					(thickness 0.1524)
				)
				(justify left)
			)
		)
		(property "Value" ""
			(at 0 0 90)
			(layer "F.Fab")
			(effects
				(font
					(size 1.27 1.27)
				)
			)
		)
		(duplicate_pad_numbers_are_jumpers no)
		(fp_line
			(start 0.7874 -0.4064)
			(end 0.7874 0.4064)
			(stroke
				(width 0.1524)
				(type default)
			)
			(layer "F.SilkS")
		)
		(fp_line
			(start -0.7874 -0.4064)
			(end 0.7874 -0.4064)
			(stroke
				(width 0.1524)
				(type default)
			)
			(layer "F.SilkS")
		)
		(fp_line
			(start 0.7874 0.4064)
			(end -0.7874 0.4064)
			(stroke
				(width 0.1524)
				(type default)
			)
			(layer "F.SilkS")
		)
		(fp_line
			(start -0.7874 0.4064)
			(end -0.7874 -0.4064)
			(stroke
				(width 0.1524)
				(type default)
			)
			(layer "F.SilkS")
		)
		(fp_poly
			(pts
				(xy -0.508 0.2794) (xy -0.508 0.2286) (xy -0.635 0.2286) (xy -0.635 -0.254) (xy -0.5334 -0.254)
				(xy -0.5334 -0.2794) (xy 0.5334 -0.2794) (xy 0.5334 -0.254) (xy 0.635 -0.254) (xy 0.635 0.254) (xy 0.5334 0.254)
				(xy 0.5334 0.2794)
			)
			(stroke
				(width 0)
				(type default)
			)
			(fill no)
			(layer "F.CrtYd")
		)
		(pad "1" smd rect
			(at 0.40005 0 90)
			(size 0.4572 0.508)
			(layers "F.Cu" "F.Mask" "F.Paste")
			(net "LPC_CPU_NODE1_LAD1")
		)
		(pad "2" smd rect
			(at -0.40005 0 90)
			(size 0.4572 0.508)
			(layers "F.Cu" "F.Mask" "F.Paste")
			(net "LPC_CPU_TPM_LAD1")
		)
	)
	(footprint ""
		(layer "F.Cu")
		(at 70.289166 -96.709992 90)
		(property "Reference" "R67"
			(at -54.98719 28.333446 90)
			(unlocked yes)
			(layer "F.SilkS")
			(effects
				(font
					(size 0.7874 0.5842)
					(thickness 0.1524)
				)
				(justify left)
			)
		)
		(property "Value" ""
			(at 0 0 90)
			(layer "F.Fab")
			(effects
				(font
					(size 1.27 1.27)
				)
			)
		)
		(duplicate_pad_numbers_are_jumpers no)
		(fp_line
			(start 0.7874 -0.4064)
			(end 0.7874 0.4064)
			(stroke
				(width 0.1524)
				(type default)
			)
			(layer "F.SilkS")
		)
		(fp_line
			(start -0.7874 -0.4064)
			(end 0.7874 -0.4064)
			(stroke
				(width 0.1524)
				(type default)
			)
			(layer "F.SilkS")
		)
		(fp_line
			(start 0.7874 0.4064)
			(end -0.7874 0.4064)
			(stroke
				(width 0.1524)
				(type default)
			)
			(layer "F.SilkS")
		)
		(fp_line
			(start -0.7874 0.4064)
			(end -0.7874 -0.4064)
			(stroke
				(width 0.1524)
				(type default)
			)
			(layer "F.SilkS")
		)
		(fp_poly
			(pts
				(xy -0.508 0.2794) (xy -0.508 0.2286) (xy -0.635 0.2286) (xy -0.635 -0.254) (xy -0.5334 -0.254)
				(xy -0.5334 -0.2794) (xy 0.5334 -0.2794) (xy 0.5334 -0.254) (xy 0.635 -0.254) (xy 0.635 0.254) (xy 0.5334 0.254)
				(xy 0.5334 0.2794)
			)
			(stroke
				(width 0)
				(type default)
			)
			(fill no)
			(layer "F.CrtYd")
		)
		(pad "1" smd rect
			(at 0.40005 0 90)
			(size 0.4572 0.508)
			(layers "F.Cu" "F.Mask" "F.Paste")
			(net "SPC_CPU_NODE1_DTR_L")
		)
		(pad "2" smd rect
			(at -0.40005 0 90)
			(size 0.4572 0.508)
			(layers "F.Cu" "F.Mask" "F.Paste")
			(net "SPC_CPU_NODE1_DCD_L")
		)
	)
	(footprint ""
		(layer "F.Cu")
		(at 153.90876 -188.126624 90)
		(property "Reference" "C663"
			(at 5.519674 -3.189732 90)
			(unlocked yes)
			(layer "F.SilkS")
			(effects
				(font
					(size 0.7874 0.5842)
					(thickness 0.1524)
				)
				(justify left)
			)
		)
		(property "Value" ""
			(at 0 0 90)
			(layer "F.Fab")
			(effects
				(font
					(size 1.27 1.27)
				)
			)
		)
		(duplicate_pad_numbers_are_jumpers no)
		(fp_line
			(start 0.7874 -0.4064)
			(end 0.7874 0.4064)
			(stroke
				(width 0.1524)
				(type default)
			)
			(layer "F.SilkS")
		)
		(fp_line
			(start -0.7874 -0.4064)
			(end 0.7874 -0.4064)
			(stroke
				(width 0.1524)
				(type default)
			)
			(layer "F.SilkS")
		)
		(fp_line
			(start 0 0.381)
			(end 0 -0.381)
			(stroke
				(width 0.1524)
				(type default)
			)
			(layer "F.SilkS")
		)
		(fp_line
			(start 0.7874 0.4064)
			(end -0.7874 0.4064)
			(stroke
				(width 0.1524)
				(type default)
			)
			(layer "F.SilkS")
		)
		(fp_line
			(start -0.7874 0.4064)
			(end -0.7874 -0.4064)
			(stroke
				(width 0.1524)
				(type default)
			)
			(layer "F.SilkS")
		)
		(fp_poly
			(pts
				(xy -0.5334 0.254) (xy -0.635 0.254) (xy -0.635 0.2286) (xy -0.635 -0.254) (xy -0.5334 -0.254) (xy -0.5334 -0.2794)
				(xy 0.5334 -0.2794) (xy 0.5334 -0.254) (xy 0.635 -0.254) (xy 0.635 0.254) (xy 0.5334 0.254) (xy 0.5334 0.2794)
				(xy -0.508 0.2794) (xy -0.5334 0.2794)
			)
			(stroke
				(width 0)
				(type default)
			)
			(fill no)
			(layer "F.CrtYd")
		)
		(pad "1" smd rect
			(at 0.40005 0 90)
			(size 0.4572 0.508)
			(layers "F.Cu" "F.Mask" "F.Paste")
			(net "T12_NODE2_EN_R")
		)
		(pad "2" smd rect
			(at -0.40005 0 90)
			(size 0.4572 0.508)
			(layers "F.Cu" "F.Mask" "F.Paste")
			(net "GND")
		)
	)
	(footprint ""
		(layer "F.Cu")
		(at 157.971998 -142.93723 -90)
		(property "Reference" "R567"
			(at -1.23063 -0.17907 90)
			(unlocked yes)
			(layer "F.SilkS")
			(effects
				(font
					(size 0.7874 0.5842)
					(thickness 0.1524)
				)
				(justify left)
			)
		)
		(property "Value" ""
			(at 0 0 270)
			(layer "F.Fab")
			(effects
				(font
					(size 1.27 1.27)
				)
			)
		)
		(duplicate_pad_numbers_are_jumpers no)
		(fp_line
			(start -0.7874 0.4064)
			(end -0.7874 -0.4064)
			(stroke
				(width 0.1524)
				(type default)
			)
			(layer "F.SilkS")
		)
		(fp_line
			(start 0.7874 0.4064)
			(end -0.7874 0.4064)
			(stroke
				(width 0.1524)
				(type default)
			)
			(layer "F.SilkS")
		)
		(fp_line
			(start -0.7874 -0.4064)
			(end 0.7874 -0.4064)
			(stroke
				(width 0.1524)
				(type default)
			)
			(layer "F.SilkS")
		)
		(fp_line
			(start 0.7874 -0.4064)
			(end 0.7874 0.4064)
			(stroke
				(width 0.1524)
				(type default)
			)
			(layer "F.SilkS")
		)
		(fp_poly
			(pts
				(xy -0.508 0.2794) (xy -0.508 0.2286) (xy -0.635 0.2286) (xy -0.635 -0.254) (xy -0.5334 -0.254)
				(xy -0.5334 -0.2794) (xy 0.5334 -0.2794) (xy 0.5334 -0.254) (xy 0.635 -0.254) (xy 0.635 0.254) (xy 0.5334 0.254)
				(xy 0.5334 0.2794)
			)
			(stroke
				(width 0)
				(type default)
			)
			(fill no)
			(layer "F.CrtYd")
		)
		(pad "1" smd rect
			(at 0.40005 0 270)
			(size 0.4572 0.508)
			(layers "F.Cu" "F.Mask" "F.Paste")
			(net "P3V3_NODE1")
		)
		(pad "2" smd rect
			(at -0.40005 0 270)
			(size 0.4572 0.508)
			(layers "F.Cu" "F.Mask" "F.Paste")
			(net "PU_LAN2_TDI")
		)
	)
	(footprint ""
		(layer "F.Cu")
		(at 49.88814 -166.43985 90)
		(property "Reference" "R562"
			(at -130.36804 -3.432048 90)
			(unlocked yes)
			(layer "F.SilkS")
			(effects
				(font
					(size 0.7874 0.5842)
					(thickness 0.1524)
				)
				(justify left)
			)
		)
		(property "Value" ""
			(at 0 0 90)
			(layer "F.Fab")
			(effects
				(font
					(size 1.27 1.27)
				)
			)
		)
		(duplicate_pad_numbers_are_jumpers no)
		(fp_line
			(start 0.7874 -0.4064)
			(end 0.7874 0.4064)
			(stroke
				(width 0.1524)
				(type default)
			)
			(layer "F.SilkS")
		)
		(fp_line
			(start -0.7874 -0.4064)
			(end 0.7874 -0.4064)
			(stroke
				(width 0.1524)
				(type default)
			)
			(layer "F.SilkS")
		)
		(fp_line
			(start 0.7874 0.4064)
			(end -0.7874 0.4064)
			(stroke
				(width 0.1524)
				(type default)
			)
			(layer "F.SilkS")
		)
		(fp_line
			(start -0.7874 0.4064)
			(end -0.7874 -0.4064)
			(stroke
				(width 0.1524)
				(type default)
			)
			(layer "F.SilkS")
		)
		(fp_poly
			(pts
				(xy -0.508 0.2794) (xy -0.508 0.2286) (xy -0.635 0.2286) (xy -0.635 -0.254) (xy -0.5334 -0.254)
				(xy -0.5334 -0.2794) (xy 0.5334 -0.2794) (xy 0.5334 -0.254) (xy 0.635 -0.254) (xy 0.635 0.254) (xy 0.5334 0.254)
				(xy 0.5334 0.2794)
			)
			(stroke
				(width 0)
				(type default)
			)
			(fill no)
			(layer "F.CrtYd")
		)
		(pad "1" smd rect
			(at 0.40005 0 90)
			(size 0.4572 0.508)
			(layers "F.Cu" "F.Mask" "F.Paste")
			(net "SMB_PCH_SDA")
		)
		(pad "2" smd rect
			(at -0.40005 0 90)
			(size 0.4572 0.508)
			(layers "F.Cu" "F.Mask" "F.Paste")
			(net "SMB_LAN1_DAT")
		)
	)
	(footprint ""
		(layer "F.Cu")
		(at 79.963518 -91.027504 180)
		(property "Reference" "R163"
			(at 1.195578 -18.973546 0)
			(unlocked yes)
			(layer "F.SilkS")
			(effects
				(font
					(size 0.7874 0.5842)
					(thickness 0.1524)
				)
				(justify left)
			)
		)
		(property "Value" ""
			(at 0 0 180)
			(layer "F.Fab")
			(effects
				(font
					(size 1.27 1.27)
				)
			)
		)
		(duplicate_pad_numbers_are_jumpers no)
		(fp_line
			(start 0.7874 0.4064)
			(end -0.7874 0.4064)
			(stroke
				(width 0.1524)
				(type default)
			)
			(layer "F.SilkS")
		)
		(fp_line
			(start 0.7874 -0.4064)
			(end 0.7874 0.4064)
			(stroke
				(width 0.1524)
				(type default)
			)
			(layer "F.SilkS")
		)
		(fp_line
			(start -0.7874 0.4064)
			(end -0.7874 -0.4064)
			(stroke
				(width 0.1524)
				(type default)
			)
			(layer "F.SilkS")
		)
		(fp_line
			(start -0.7874 -0.4064)
			(end 0.7874 -0.4064)
			(stroke
				(width 0.1524)
				(type default)
			)
			(layer "F.SilkS")
		)
		(fp_poly
			(pts
				(xy -0.508 0.2794) (xy -0.508 0.2286) (xy -0.635 0.2286) (xy -0.635 -0.254) (xy -0.5334 -0.254)
				(xy -0.5334 -0.2794) (xy 0.5334 -0.2794) (xy 0.5334 -0.254) (xy 0.635 -0.254) (xy 0.635 0.254) (xy 0.5334 0.254)
				(xy 0.5334 0.2794)
			)
			(stroke
				(width 0)
				(type default)
			)
			(fill no)
			(layer "F.CrtYd")
		)
		(pad "1" smd rect
			(at 0.40005 0 180)
			(size 0.4572 0.508)
			(layers "F.Cu" "F.Mask" "F.Paste")
			(net "VR_CPU_NODE1_INTVRMEN")
		)
		(pad "2" smd rect
			(at -0.40005 0 180)
			(size 0.4572 0.508)
			(layers "F.Cu" "F.Mask" "F.Paste")
			(net "P3V3_RTC_NODE1")
		)
	)
	(footprint ""
		(layer "F.Cu")
		(at 44.625006 -182.898542 180)
		(property "Reference" "U93"
			(at -0.055118 5.057394 0)
			(unlocked yes)
			(layer "F.SilkS")
			(effects
				(font
					(size 0.7874 0.5842)
					(thickness 0.1524)
				)
			)
		)
		(property "Value" ""
			(at 0 0 180)
			(layer "F.Fab")
			(effects
				(font
					(size 1.27 1.27)
				)
			)
		)
		(duplicate_pad_numbers_are_jumpers no)
		(fp_line
			(start 1.651 1.905)
			(end -1.651 1.905)
			(stroke
				(width 0.1524)
				(type default)
			)
			(layer "F.SilkS")
		)
		(fp_line
			(start 1.651 -1.905)
			(end 1.651 1.905)
			(stroke
				(width 0.1524)
				(type default)
			)
			(layer "F.SilkS")
		)
		(fp_line
			(start -1.651 1.905)
			(end -1.651 -1.905)
			(stroke
				(width 0.1524)
				(type default)
			)
			(layer "F.SilkS")
		)
		(fp_line
			(start -1.651 -1.905)
			(end 1.651 -1.905)
			(stroke
				(width 0.1524)
				(type default)
			)
			(layer "F.SilkS")
		)
		(fp_poly
			(pts
				(xy -1.524 0.7112) (xy -1.524 1.7526) (xy -0.508 1.7526) (xy -0.508 0.6985) (xy 0.508 0.6985) (xy 0.508 1.7526)
				(xy 1.524 1.7526) (xy 1.524 0.6985) (xy 1.524 -0.6985) (xy 0.508 -0.6985) (xy 0.508 -1.7526) (xy -0.508 -1.7526)
				(xy -0.508 -0.6985) (xy -1.524 -0.6985) (xy -1.524 0.6985)
			)
			(stroke
				(width 0)
				(type default)
			)
			(fill no)
			(layer "F.CrtYd")
		)
		(fp_text user "D"
			(at 2.021586 -1.39192 0)
			(unlocked yes)
			(layer "F.SilkS")
			(effects
				(font
					(size 0.635 0.4064)
					(thickness 0.1524)
				)
			)
		)
		(fp_text user "S"
			(at 1.662176 2.46507 0)
			(unlocked yes)
			(layer "F.SilkS")
			(effects
				(font
					(size 0.635 0.4064)
					(thickness 0.1524)
				)
			)
		)
		(fp_text user "G"
			(at 0.580644 2.230374 0)
			(unlocked yes)
			(layer "F.SilkS")
			(effects
				(font
					(size 0.635 0.4064)
					(thickness 0.1524)
				)
			)
		)
		(pad "D" smd rect
			(at 0 -1.1176 180)
			(size 1.016 1.27)
			(layers "F.Cu" "F.Mask" "F.Paste")
			(net "P12V_AUX_EN")
		)
		(pad "G" smd rect
			(at -1.016 1.1176 180)
			(size 1.016 1.27)
			(layers "F.Cu" "F.Mask" "F.Paste")
			(net "MATE_N")
		)
		(pad "S" smd rect
			(at 1.016 1.1176 180)
			(size 1.016 1.27)
			(layers "F.Cu" "F.Mask" "F.Paste")
			(net "GND")
		)
	)
	(footprint ""
		(layer "F.Cu")
		(at 26.91892 -137.846308 180)
		(property "Reference" "C431"
			(at -2.42062 -0.05334 0)
			(unlocked yes)
			(layer "F.SilkS")
			(effects
				(font
					(size 0.7874 0.5842)
					(thickness 0.1524)
				)
				(justify left)
			)
		)
		(property "Value" ""
			(at 0 0 180)
			(layer "F.Fab")
			(effects
				(font
					(size 1.27 1.27)
				)
			)
		)
		(duplicate_pad_numbers_are_jumpers no)
		(fp_line
			(start 1.905 0.8636)
			(end -1.905 0.8636)
			(stroke
				(width 0.1524)
				(type default)
			)
			(layer "F.SilkS")
		)
		(fp_line
			(start 1.905 -0.8636)
			(end 1.905 0.8636)
			(stroke
				(width 0.1524)
				(type default)
			)
			(layer "F.SilkS")
		)
		(fp_line
			(start 0 0.8382)
			(end 0 -0.8382)
			(stroke
				(width 0.1524)
				(type default)
			)
			(layer "F.SilkS")
		)
		(fp_line
			(start -1.905 0.8636)
			(end -1.905 -0.8636)
			(stroke
				(width 0.1524)
				(type default)
			)
			(layer "F.SilkS")
		)
		(fp_line
			(start -1.905 -0.8636)
			(end 1.905 -0.8636)
			(stroke
				(width 0.1524)
				(type default)
			)
			(layer "F.SilkS")
		)
		(fp_rect
			(start -1.524 0.7366)
			(end 1.524 -0.7366)
			(stroke
				(width 0)
				(type default)
			)
			(fill no)
			(layer "F.CrtYd")
		)
		(pad "1" smd rect
			(at 0.94996 0 180)
			(size 1.1176 1.3716)
			(layers "F.Cu" "F.Mask" "F.Paste")
			(net "P1V9_LAN1")
		)
		(pad "2" smd rect
			(at -0.94996 0 180)
			(size 1.1176 1.3716)
			(layers "F.Cu" "F.Mask" "F.Paste")
			(net "GND")
		)
	)
)
